# BASEBOARD_FAB2 (Tioga Pass) — schematic netlist excerpt (pin names and nets, part order shuffled) for the footprints in the layout excerpt that follows; sources: Cadence DE-HDL packaged netlist, KiCad conversion of Wiwynn_Tioga_Pass_MB.brd

C3N12  CAP_A  22.0UF 4V 20% X6S  pkg 0603V  page 132 : A = PVNN_PCH_STBY ; B = GND
C9N11  CAPP  470UF 2.5V 20% ALUM  pkg 3018  page 210 : A = PVSA_CPU1 ; B = GND
C8L12  CAP_A  47UF 4V 20% X5R  pkg 0603V  page 228 : A = PVDDQ_KLM ; B = GND

(kicad_pcb
	(version 20260206)
	(generator "pcbnew")
	(generator_version "10.0")
	(general
		(thickness 1.6)
		(legacy_teardrops no)
	)
	(paper "A4")
	(title_block
		(title "Wiwynn_Tioga_Pass_MB.brd")
		(comment 1 "Tioga Pass / footprints 2425-2427 of 4770")
	)
	(layers
		(0 "F.Cu" signal "TOP")
		(4 "In1.Cu" signal "L2GND")
		(6 "In2.Cu" signal "L3")
		(8 "In3.Cu" signal "L4GND")
		(10 "In4.Cu" signal "L5")
		(12 "In5.Cu" signal "L6GND")
		(14 "In6.Cu" signal "L7VCC")
		(16 "In7.Cu" signal "L8VCC")
		(18 "In8.Cu" signal "L9GND")
		(20 "In9.Cu" signal "L10")
		(22 "In10.Cu" signal "L11GND")
		(24 "In11.Cu" signal "L12")
		(26 "In12.Cu" signal "L13GND")
		(2 "B.Cu" signal "BOTTOM")
		(9 "F.Adhes" user "F.Adhesive")
		(11 "B.Adhes" user "B.Adhesive")
		(13 "F.Paste" user "Package Geometry/Pastemask Top")
		(15 "B.Paste" user "Package Geometry/Pastemask Bottom")
		(5 "F.SilkS" user "Ref Des/Silkscreen Top")
		(7 "B.SilkS" user "Ref Des/Silkscreen Bottom")
		(1 "F.Mask" user "Board Geometry/Soldermask Top")
		(3 "B.Mask" user "Board Geometry/Soldermask Bottom")
		(17 "Dwgs.User" user "User.Drawings")
		(19 "Cmts.User" user "User.Comments")
		(21 "Eco1.User" user "User.Eco1")
		(23 "Eco2.User" user "User.Eco2")
		(25 "Edge.Cuts" user "Board Geometry/Outline")
		(27 "Margin" user)
		(31 "F.CrtYd" user "Package Geometry/Place Bound Top")
		(29 "B.CrtYd" user "Package Geometry/Place Bound Bottom")
		(35 "F.Fab" user "Ref Des/Assembly Top")
		(33 "B.Fab" user "Ref Des/Assembly Bottom")
	)
	(footprint ""
		(layer "B.Cu")
		(at 93.086428 -144.89684 -90)
		(property "Reference" "C8L12"
			(at 0 0 90)
			(layer "B.SilkS")
			(hide yes)
			(effects
				(font
					(size 1.27 1.27)
				)
				(justify mirror)
			)
		)
		(property "Value" ""
			(at 0 0 90)
			(layer "B.Fab")
			(effects
				(font
					(size 1.27 1.27)
				)
				(justify mirror)
			)
		)
		(duplicate_pad_numbers_are_jumpers no)
		(fp_rect
			(start 0.500126 1.598422)
			(end -0.500126 -0.201422)
			(stroke
				(width 0)
				(type default)
			)
			(fill no)
			(layer "B.CrtYd")
		)
		(fp_line
			(start -0.500126 1.598422)
			(end 0.500126 1.598422)
			(stroke
				(width 0.1)
				(type default)
			)
			(layer "B.Fab")
		)
		(fp_line
			(start 0.500126 1.598422)
			(end 0.500126 -0.201422)
			(stroke
				(width 0.1)
				(type default)
			)
			(layer "B.Fab")
		)
		(fp_line
			(start -0.500126 -0.201422)
			(end -0.500126 1.598422)
			(stroke
				(width 0.1)
				(type default)
			)
			(layer "B.Fab")
		)
		(fp_line
			(start 0.500126 -0.201422)
			(end -0.500126 -0.201422)
			(stroke
				(width 0.1)
				(type default)
			)
			(layer "B.Fab")
		)
		(pad "1" smd rect
			(at 0 0 180)
			(size 0.889 0.9906)
			(layers "B.Cu" "B.Mask" "B.Paste")
			(net "PVDDQ_KLM")
		)
		(pad "2" smd rect
			(at 0 1.397 180)
			(size 0.889 0.9906)
			(layers "B.Cu" "B.Mask" "B.Paste")
			(net "GND")
		)
		(zone
			(layer "B.Cu")
			(hatch none 0.5)
			(connect_pads
				(clearance 0)
			)
			(min_thickness 0.25)
			(keepout
				(tracks not_allowed)
				(vias allowed)
				(pads allowed)
				(copperpour not_allowed)
				(footprints allowed)
			)
			(placement
				(enabled no)
				(sheetname "")
			)
			(fill
				(thermal_gap 0.5)
				(thermal_bridge_width 0.5)
				(island_removal_mode 0)
			)
			(polygon
				(pts
					(xy 92.133928 -144.40154) (xy 92.641928 -144.40154) (xy 92.641928 -145.39214) (xy 92.133928 -145.39214)
				)
			)
		)
		(zone
			(layer "B.Cu")
			(hatch none 0.5)
			(connect_pads
				(clearance 0)
			)
			(min_thickness 0.25)
			(keepout
				(tracks allowed)
				(vias not_allowed)
				(pads allowed)
				(copperpour not_allowed)
				(footprints allowed)
			)
			(placement
				(enabled no)
				(sheetname "")
			)
			(fill
				(thermal_gap 0.5)
				(thermal_bridge_width 0.5)
				(island_removal_mode 0)
			)
			(polygon
				(pts
					(xy 92.133928 -144.40154) (xy 92.641928 -144.40154) (xy 92.641928 -145.39214) (xy 92.133928 -145.39214)
				)
			)
		)
	)
	(footprint ""
		(layer "B.Cu")
		(at 45.611796 -100.676202 -90)
		(property "Reference" "C9N11"
			(at -0.008128 -3.664204 0)
			(unlocked yes)
			(layer "B.SilkS")
			(effects
				(font
					(size 0.7874 0.5842)
					(thickness 0.1524)
				)
				(justify mirror)
			)
		)
		(property "Value" ""
			(at 0 0 90)
			(layer "B.Fab")
			(effects
				(font
					(size 1.27 1.27)
				)
				(justify mirror)
			)
		)
		(duplicate_pad_numbers_are_jumpers no)
		(fp_line
			(start -2.286 7.366)
			(end -1.600708 7.366)
			(stroke
				(width 0.1524)
				(type default)
			)
			(layer "B.SilkS")
		)
		(fp_line
			(start -2.286 7.366)
			(end -2.286 1.63195)
			(stroke
				(width 0.1524)
				(type default)
			)
			(layer "B.SilkS")
		)
		(fp_line
			(start 2.286 7.366)
			(end 1.60147 7.366)
			(stroke
				(width 0.1524)
				(type default)
			)
			(layer "B.SilkS")
		)
		(fp_line
			(start 2.286 7.366)
			(end 2.286 1.632712)
			(stroke
				(width 0.1524)
				(type default)
			)
			(layer "B.SilkS")
		)
		(fp_line
			(start -2.504948 1.633728)
			(end -1.6002 1.633728)
			(stroke
				(width 0.1524)
				(type default)
			)
			(layer "B.SilkS")
		)
		(fp_line
			(start 2.563114 1.633728)
			(end 1.6002 1.633728)
			(stroke
				(width 0.1524)
				(type default)
			)
			(layer "B.SilkS")
		)
		(fp_line
			(start -2.504948 -1.616456)
			(end -2.504948 1.633728)
			(stroke
				(width 0.1524)
				(type default)
			)
			(layer "B.SilkS")
		)
		(fp_line
			(start -1.6002 -1.616456)
			(end -2.504948 -1.616456)
			(stroke
				(width 0.1524)
				(type default)
			)
			(layer "B.SilkS")
		)
		(fp_line
			(start 1.6002 -1.616456)
			(end 2.563114 -1.616456)
			(stroke
				(width 0.1524)
				(type default)
			)
			(layer "B.SilkS")
		)
		(fp_line
			(start 2.563114 -1.616456)
			(end 2.563114 1.633728)
			(stroke
				(width 0.1524)
				(type default)
			)
			(layer "B.SilkS")
		)
		(fp_rect
			(start 2.286 7.366)
			(end -2.286 -0.254)
			(stroke
				(width 0)
				(type default)
			)
			(fill no)
			(layer "B.CrtYd")
		)
		(fp_line
			(start -2.286 7.366)
			(end 2.286 7.366)
			(stroke
				(width 0.1)
				(type default)
			)
			(layer "B.Fab")
		)
		(fp_line
			(start 2.286 7.366)
			(end 2.286 -0.254)
			(stroke
				(width 0.1)
				(type default)
			)
			(layer "B.Fab")
		)
		(fp_line
			(start -2.286 -0.254)
			(end -2.286 7.366)
			(stroke
				(width 0.1)
				(type default)
			)
			(layer "B.Fab")
		)
		(fp_line
			(start 2.286 -0.254)
			(end -2.286 -0.254)
			(stroke
				(width 0.1)
				(type default)
			)
			(layer "B.Fab")
		)
		(pad "1" smd rect
			(at 0 0 90)
			(size 2.54 3.048)
			(layers "B.Cu" "B.Mask" "B.Paste")
			(net "PVSA_CPU1")
		)
		(pad "2" smd rect
			(at 0 7.112 90)
			(size 2.54 3.048)
			(layers "B.Cu" "B.Mask" "B.Paste")
			(net "GND")
		)
	)
	(footprint ""
		(layer "B.Cu")
		(at 388.1374 -109.7534)
		(property "Reference" "C3N12"
			(at 0 0 0)
			(layer "B.SilkS")
			(hide yes)
			(effects
				(font
					(size 1.27 1.27)
				)
				(justify mirror)
			)
		)
		(property "Value" ""
			(at 0 0 0)
			(layer "B.Fab")
			(effects
				(font
					(size 1.27 1.27)
				)
				(justify mirror)
			)
		)
		(duplicate_pad_numbers_are_jumpers no)
		(fp_poly
			(pts
				(xy 0.4953 -0.2032) (xy -0.4953 -0.2032) (xy -0.4953 1.6002) (xy 0.4953 1.6002)
			)
			(stroke
				(width 0)
				(type default)
			)
			(fill no)
			(layer "B.CrtYd")
		)
		(fp_line
			(start -0.4953 -0.2032)
			(end -0.4953 1.6002)
			(stroke
				(width 0.1)
				(type default)
			)
			(layer "B.Fab")
		)
		(fp_line
			(start -0.4953 1.6002)
			(end 0.4953 1.6002)
			(stroke
				(width 0.1)
				(type default)
			)
			(layer "B.Fab")
		)
		(fp_line
			(start 0.4953 -0.2032)
			(end -0.4953 -0.2032)
			(stroke
				(width 0.1)
				(type default)
			)
			(layer "B.Fab")
		)
		(fp_line
			(start 0.4953 1.6002)
			(end 0.4953 -0.2032)
			(stroke
				(width 0.1)
				(type default)
			)
			(layer "B.Fab")
		)
		(pad "1" smd rect
			(at 0 0 180)
			(size 0.762 0.889)
			(layers "B.Cu" "B.Mask" "B.Paste")
			(net "PVNN_PCH_STBY")
		)
		(pad "2" smd rect
			(at 0 1.397 180)
			(size 0.762 0.889)
			(layers "B.Cu" "B.Mask" "B.Paste")
			(net "GND")
		)
		(zone
			(layer "B.Cu")
			(hatch none 0.5)
			(connect_pads
				(clearance 0)
			)
			(min_thickness 0.25)
			(keepout
				(tracks not_allowed)
				(vias allowed)
				(pads allowed)
				(copperpour not_allowed)
				(footprints allowed)
			)
			(placement
				(enabled no)
				(sheetname "")
			)
			(fill
				(thermal_gap 0.5)
				(thermal_bridge_width 0.5)
				(island_removal_mode 0)
			)
			(polygon
				(pts
					(xy 388.5184 -109.3089) (xy 387.7564 -109.3089) (xy 387.7564 -108.8009) (xy 388.5184 -108.8009)
				)
			)
		)
	)
)
